# T6G (Grand Teton) — schematic netlist excerpt (pin names and nets, part order shuffled) for the footprints in the layout excerpt that follows; sources: Cadence DE-HDL packaged netlist, KiCad conversion of 04192023_DAF0TMB3IC0_F0TG_MB_C_brd_V02_OCP.brd

R1051  Q_RES  0 5% EMPTY  pkg 0603LF  page 301 : A = P0V9_CPU0_RT_2D ; B = P0V9_CPU0_RT2_2A_2D
R1365  Q_RES  4.7K 5% CHIP  pkg 0201LF  page 276 : A = JTAG_TCK_RT_CPU0_P0 ; B = GND
R987  Q_RES  0 5% EMPTY  pkg 0402LF  page 159 : A = I3C_1_SPD_DDRGL_CPU0_R_SDA ; B = I3C_SPD_DDRGL_CPU0_BYPASS_SDA

(kicad_pcb
	(version 20260206)
	(generator "pcbnew")
	(generator_version "10.0")
	(general
		(thickness 1.6)
		(legacy_teardrops no)
	)
	(paper "A4")
	(title_block
		(title "04192023_DAF0TMB3IC0_F0TG_MB_C_brd_V02_OCP.brd")
		(comment 1 "Grand Teton / footprints 5430-5432 of 8354")
	)
	(layers
		(0 "F.Cu" signal "TOP")
		(4 "In1.Cu" signal "GND")
		(6 "In2.Cu" signal "IN1")
		(8 "In3.Cu" signal "GND1")
		(10 "In4.Cu" signal "IN2")
		(12 "In5.Cu" signal "GND2")
		(14 "In6.Cu" signal "IN3")
		(16 "In7.Cu" signal "GND3")
		(18 "In8.Cu" signal "VCC")
		(20 "In9.Cu" signal "VCC1")
		(22 "In10.Cu" signal "GND4")
		(24 "In11.Cu" signal "IN4")
		(26 "In12.Cu" signal "GND5")
		(28 "In13.Cu" signal "IN5")
		(30 "In14.Cu" signal "GND6")
		(32 "In15.Cu" signal "IN6")
		(34 "In16.Cu" signal "GND7")
		(2 "B.Cu" signal "BOTTOM")
		(9 "F.Adhes" user "F.Adhesive")
		(11 "B.Adhes" user "B.Adhesive")
		(13 "F.Paste" user "Package Geometry/Pastemask Top")
		(15 "B.Paste" user "Package Geometry/Pastemask Bottom")
		(5 "F.SilkS" user "Ref Des/Silkscreen Top")
		(7 "B.SilkS" user "Ref Des/Silkscreen Bottom")
		(1 "F.Mask" user "Board Geometry/Soldermask Top")
		(3 "B.Mask" user "Board Geometry/Soldermask Bottom")
		(17 "Dwgs.User" user "User.Drawings")
		(19 "Cmts.User" user "User.Comments")
		(21 "Eco1.User" user "User.Eco1")
		(23 "Eco2.User" user "User.Eco2")
		(25 "Edge.Cuts" user "Board Geometry/Outline")
		(27 "Margin" user)
		(31 "F.CrtYd" user "Package Geometry/Place Bound Top")
		(29 "B.CrtYd" user "Package Geometry/Place Bound Bottom")
		(35 "F.Fab" user "Ref Des/Assembly Top")
		(33 "B.Fab" user "Ref Des/Assembly Bottom")
	)
	(footprint ""
		(layer "B.Cu")
		(at 395.516354 -401.624546 180)
		(property "Reference" "R1051"
			(at 0 0 0)
			(layer "B.SilkS")
			(hide yes)
			(effects
				(font
					(size 1.27 1.27)
				)
				(justify mirror)
			)
		)
		(property "Value" ""
			(at 0 0 0)
			(layer "B.Fab")
			(effects
				(font
					(size 1.27 1.27)
				)
				(justify mirror)
			)
		)
		(duplicate_pad_numbers_are_jumpers no)
		(fp_line
			(start 1.2954 0.5842)
			(end 1.2954 -0.5842)
			(stroke
				(width 0.1524)
				(type default)
			)
			(layer "B.SilkS")
		)
		(fp_line
			(start 1.2954 -0.5842)
			(end -1.2954 -0.5842)
			(stroke
				(width 0.1524)
				(type default)
			)
			(layer "B.SilkS")
		)
		(fp_line
			(start -1.2954 0.5842)
			(end 1.2954 0.5842)
			(stroke
				(width 0.1524)
				(type default)
			)
			(layer "B.SilkS")
		)
		(fp_line
			(start -1.2954 -0.5842)
			(end -1.2954 0.5842)
			(stroke
				(width 0.1524)
				(type default)
			)
			(layer "B.SilkS")
		)
		(fp_line
			(start 1.1938 0.4064)
			(end 1.1938 -0.406654)
			(stroke
				(width 0.1)
				(type default)
			)
			(layer "B.Fab")
		)
		(fp_line
			(start 1.1938 -0.406654)
			(end 0.8636 -0.406654)
			(stroke
				(width 0.1)
				(type default)
			)
			(layer "B.Fab")
		)
		(fp_line
			(start 0.8636 0.4572)
			(end 0.8636 0.4318)
			(stroke
				(width 0.1)
				(type default)
			)
			(layer "B.Fab")
		)
		(fp_line
			(start 0.8636 0.4318)
			(end 0.8636 0.4064)
			(stroke
				(width 0.1)
				(type default)
			)
			(layer "B.Fab")
		)
		(fp_line
			(start 0.8636 0.4064)
			(end 1.1938 0.4064)
			(stroke
				(width 0.1)
				(type default)
			)
			(layer "B.Fab")
		)
		(fp_line
			(start 0.8636 -0.406654)
			(end 0.8636 -0.4572)
			(stroke
				(width 0.1)
				(type default)
			)
			(layer "B.Fab")
		)
		(fp_line
			(start 0.8636 -0.4572)
			(end -0.8636 -0.4572)
			(stroke
				(width 0.1)
				(type default)
			)
			(layer "B.Fab")
		)
		(fp_line
			(start -0.8636 0.4572)
			(end 0.8636 0.4572)
			(stroke
				(width 0.1)
				(type default)
			)
			(layer "B.Fab")
		)
		(fp_line
			(start -0.8636 0.4064)
			(end -0.8636 0.4572)
			(stroke
				(width 0.1)
				(type default)
			)
			(layer "B.Fab")
		)
		(fp_line
			(start -0.8636 -0.406654)
			(end -1.1938 -0.406654)
			(stroke
				(width 0.1)
				(type default)
			)
			(layer "B.Fab")
		)
		(fp_line
			(start -0.8636 -0.4572)
			(end -0.8636 -0.406654)
			(stroke
				(width 0.1)
				(type default)
			)
			(layer "B.Fab")
		)
		(fp_line
			(start -1.1938 0.4064)
			(end -0.8636 0.4064)
			(stroke
				(width 0.1)
				(type default)
			)
			(layer "B.Fab")
		)
		(fp_line
			(start -1.1938 -0.406654)
			(end -1.1938 0.4064)
			(stroke
				(width 0.1)
				(type default)
			)
			(layer "B.Fab")
		)
		(pad "1" smd rect
			(at 0.7366 0 90)
			(size 0.7112 0.8128)
			(layers "B.Cu" "B.Mask" "B.Paste")
			(net "P0V9_CPU0_RT_2D")
		)
		(pad "2" smd rect
			(at -0.7366 0 90)
			(size 0.7112 0.8128)
			(layers "B.Cu" "B.Mask" "B.Paste")
			(net "P0V9_CPU0_RT2_2A_2D")
		)
	)
	(footprint ""
		(layer "B.Cu")
		(at 383.076958 -205.902052 -90)
		(property "Reference" "R987"
			(at 0 0 90)
			(layer "B.SilkS")
			(hide yes)
			(effects
				(font
					(size 1.27 1.27)
				)
				(justify mirror)
			)
		)
		(property "Value" ""
			(at 0 0 90)
			(layer "B.Fab")
			(effects
				(font
					(size 1.27 1.27)
				)
				(justify mirror)
			)
		)
		(duplicate_pad_numbers_are_jumpers no)
		(fp_line
			(start -0.7874 0.4064)
			(end 0.7874 0.4064)
			(stroke
				(width 0.1524)
				(type default)
			)
			(layer "B.SilkS")
		)
		(fp_line
			(start 0.7874 0.4064)
			(end 0.7874 -0.4064)
			(stroke
				(width 0.1524)
				(type default)
			)
			(layer "B.SilkS")
		)
		(fp_line
			(start -0.7874 -0.4064)
			(end -0.7874 0.4064)
			(stroke
				(width 0.1524)
				(type default)
			)
			(layer "B.SilkS")
		)
		(fp_line
			(start 0.7874 -0.4064)
			(end -0.7874 -0.4064)
			(stroke
				(width 0.1524)
				(type default)
			)
			(layer "B.SilkS")
		)
		(fp_line
			(start -0.67945 0.3048)
			(end -0.120396 0.3048)
			(stroke
				(width 0.1)
				(type default)
			)
			(layer "B.Fab")
		)
		(fp_line
			(start -0.120396 0.3048)
			(end -0.120396 0.2794)
			(stroke
				(width 0.1)
				(type default)
			)
			(layer "B.Fab")
		)
		(fp_line
			(start 0.12065 0.3048)
			(end 0.67945 0.3048)
			(stroke
				(width 0.1)
				(type default)
			)
			(layer "B.Fab")
		)
		(fp_line
			(start 0.67945 0.3048)
			(end 0.67945 -0.305054)
			(stroke
				(width 0.1)
				(type default)
			)
			(layer "B.Fab")
		)
		(fp_line
			(start -0.120396 0.2794)
			(end 0.12065 0.2794)
			(stroke
				(width 0.1)
				(type default)
			)
			(layer "B.Fab")
		)
		(fp_line
			(start 0.12065 0.2794)
			(end 0.12065 0.3048)
			(stroke
				(width 0.1)
				(type default)
			)
			(layer "B.Fab")
		)
		(fp_line
			(start -0.12065 -0.2794)
			(end -0.12065 -0.3048)
			(stroke
				(width 0.1)
				(type default)
			)
			(layer "B.Fab")
		)
		(fp_line
			(start 0.12065 -0.2794)
			(end -0.12065 -0.2794)
			(stroke
				(width 0.1)
				(type default)
			)
			(layer "B.Fab")
		)
		(fp_line
			(start -0.67945 -0.3048)
			(end -0.67945 0.3048)
			(stroke
				(width 0.1)
				(type default)
			)
			(layer "B.Fab")
		)
		(fp_line
			(start -0.12065 -0.3048)
			(end -0.67945 -0.3048)
			(stroke
				(width 0.1)
				(type default)
			)
			(layer "B.Fab")
		)
		(fp_line
			(start 0.12065 -0.305054)
			(end 0.12065 -0.2794)
			(stroke
				(width 0.1)
				(type default)
			)
			(layer "B.Fab")
		)
		(fp_line
			(start 0.67945 -0.305054)
			(end 0.12065 -0.305054)
			(stroke
				(width 0.1)
				(type default)
			)
			(layer "B.Fab")
		)
		(pad "1" smd rect
			(at 0.40005 0 270)
			(size 0.4572 0.508)
			(layers "B.Cu" "B.Mask" "B.Paste")
			(net "I3C_1_SPD_DDRGL_CPU0_R_SDA")
		)
		(pad "2" smd rect
			(at -0.40005 0 270)
			(size 0.4572 0.508)
			(layers "B.Cu" "B.Mask" "B.Paste")
			(net "I3C_SPD_DDRGL_CPU0_BYPASS_SDA")
		)
	)
	(footprint ""
		(layer "B.Cu")
		(at 307.0352 -428.0916 180)
		(property "Reference" "R1365"
			(at 0 0 0)
			(layer "B.SilkS")
			(hide yes)
			(effects
				(font
					(size 1.27 1.27)
				)
				(justify mirror)
			)
		)
		(property "Value" ""
			(at 0 0 0)
			(layer "B.Fab")
			(effects
				(font
					(size 1.27 1.27)
				)
				(justify mirror)
			)
		)
		(duplicate_pad_numbers_are_jumpers no)
		(fp_line
			(start 0.32512 0.175006)
			(end 0.32512 -0.175006)
			(stroke
				(width 0.1)
				(type default)
			)
			(layer "B.Fab")
		)
		(fp_line
			(start 0.32512 -0.175006)
			(end -0.32512 -0.175006)
			(stroke
				(width 0.1)
				(type default)
			)
			(layer "B.Fab")
		)
		(fp_line
			(start -0.32512 0.175006)
			(end 0.32512 0.175006)
			(stroke
				(width 0.1)
				(type default)
			)
			(layer "B.Fab")
		)
		(fp_line
			(start -0.32512 -0.175006)
			(end -0.32512 0.175006)
			(stroke
				(width 0.1)
				(type default)
			)
			(layer "B.Fab")
		)
		(pad "1" smd rect
			(at 0.2667 0)
			(size 0.3048 0.381)
			(layers "B.Cu" "B.Mask" "B.Paste")
			(net "JTAG_TCK_RT_CPU0_P0")
		)
		(pad "2" smd rect
			(at -0.2667 0 180)
			(size 0.3048 0.381)
			(layers "B.Cu" "B.Mask" "B.Paste")
			(net "GND")
		)
	)
)
